(kicad_pcb
	(version 20260206)
	(generator "pcbnew")
	(generator_version "10.0")
	(general
		(thickness 1.6)
		(legacy_teardrops no)
	)
	(paper "A4")
	(title_block
		(title "04192023_DAF0TMB3IC0_F0TG_MB_C_brd_V02_OCP.brd")
		(comment 1 "Grand Teton / footprint 2100 of 8354 (J24), pads 227-291 of 291")
	)
	(layers
		(0 "F.Cu" signal "TOP")
		(4 "In1.Cu" signal "GND")
		(6 "In2.Cu" signal "IN1")
		(8 "In3.Cu" signal "GND1")
		(10 "In4.Cu" signal "IN2")
		(12 "In5.Cu" signal "GND2")
		(14 "In6.Cu" signal "IN3")
		(16 "In7.Cu" signal "GND3")
		(18 "In8.Cu" signal "VCC")
		(20 "In9.Cu" signal "VCC1")
		(22 "In10.Cu" signal "GND4")
		(24 "In11.Cu" signal "IN4")
		(26 "In12.Cu" signal "GND5")
		(28 "In13.Cu" signal "IN5")
		(30 "In14.Cu" signal "GND6")
		(32 "In15.Cu" signal "IN6")
		(34 "In16.Cu" signal "GND7")
		(2 "B.Cu" signal "BOTTOM")
		(9 "F.Adhes" user "F.Adhesive")
		(11 "B.Adhes" user "B.Adhesive")
		(13 "F.Paste" user "Package Geometry/Pastemask Top")
		(15 "B.Paste" user "Package Geometry/Pastemask Bottom")
		(5 "F.SilkS" user "Ref Des/Silkscreen Top")
		(7 "B.SilkS" user "Ref Des/Silkscreen Bottom")
		(1 "F.Mask" user "Board Geometry/Soldermask Top")
		(3 "B.Mask" user "Board Geometry/Soldermask Bottom")
		(17 "Dwgs.User" user "User.Drawings")
		(19 "Cmts.User" user "User.Comments")
		(21 "Eco1.User" user "User.Eco1")
		(23 "Eco2.User" user "User.Eco2")
		(25 "Edge.Cuts" user "Board Geometry/Outline")
		(27 "Margin" user)
		(31 "F.CrtYd" user "Package Geometry/Place Bound Top")
		(29 "B.CrtYd" user "Package Geometry/Place Bound Bottom")
		(35 "F.Fab" user "Ref Des/Assembly Top")
		(33 "B.Fab" user "Ref Des/Assembly Bottom")
	)
	(footprint ""
		(layer "F.Cu")
		(at 57.378092 -255.560322 180)
		(property "Reference" "J24"
			(at 1.914906 -84.58708 0)
			(unlocked yes)
			(layer "F.SilkS")
			(effects
				(font
					(size 0.7874 0.5842)
					(thickness 0.1524)
				)
			)
		)
		(property "Value" ""
			(at 0 0 180)
			(layer "F.Fab")
			(effects
				(font
					(size 1.27 1.27)
				)
			)
		)
		(duplicate_pad_numbers_are_jumpers no)
		(pad "227" smd rect
			(at 2.050034 11.474958 90)
			(size 0.519938 1.4986)
			(layers "F.Cu" "F.Mask" "F.Paste")
			(net "M_A_CPU1_SB_PAR")
		)
		(pad "228" smd rect
			(at 2.050034 12.325096 90)
			(size 0.519938 1.4986)
			(layers "F.Cu" "F.Mask" "F.Paste")
			(net "GND")
		)
		(pad "229" smd rect
			(at 2.050034 13.17498 90)
			(size 0.519938 1.4986)
			(layers "F.Cu" "F.Mask" "F.Paste")
			(net "M_A_CPU1_SB_CS_N<1>")
		)
		(pad "230" smd rect
			(at 2.050034 14.025118 90)
			(size 0.519938 1.4986)
			(layers "F.Cu" "F.Mask" "F.Paste")
			(net "GND")
		)
		(pad "231" smd rect
			(at 2.050034 14.875002 90)
			(size 0.519938 1.4986)
			(layers "F.Cu" "F.Mask" "F.Paste")
			(net "Net_2261")
		)
		(pad "232" smd rect
			(at 2.050034 15.724886 90)
			(size 0.519938 1.4986)
			(layers "F.Cu" "F.Mask" "F.Paste")
			(net "Net_2262")
		)
		(pad "233" smd rect
			(at 2.050034 16.575024 90)
			(size 0.519938 1.4986)
			(layers "F.Cu" "F.Mask" "F.Paste")
			(net "GND")
		)
		(pad "234" smd rect
			(at 2.050034 17.424908 90)
			(size 0.519938 1.4986)
			(layers "F.Cu" "F.Mask" "F.Paste")
			(net "M_A_CPU1_SB_CB<6>")
		)
		(pad "235" smd rect
			(at 2.050034 18.275046 90)
			(size 0.519938 1.4986)
			(layers "F.Cu" "F.Mask" "F.Paste")
			(net "GND")
		)
		(pad "236" smd rect
			(at 2.050034 19.12493 90)
			(size 0.519938 1.4986)
			(layers "F.Cu" "F.Mask" "F.Paste")
			(net "M_A_CPU1_SB_CB<7>")
		)
		(pad "237" smd rect
			(at 2.050034 19.975068 90)
			(size 0.519938 1.4986)
			(layers "F.Cu" "F.Mask" "F.Paste")
			(net "GND")
		)
		(pad "238" smd rect
			(at 2.050034 20.824952 90)
			(size 0.519938 1.4986)
			(layers "F.Cu" "F.Mask" "F.Paste")
			(net "M_A_CPU1_SB_DQS_DN<4>")
		)
		(pad "239" smd rect
			(at 2.050034 21.67509 90)
			(size 0.519938 1.4986)
			(layers "F.Cu" "F.Mask" "F.Paste")
			(net "M_A_CPU1_SB_DQS_DP<4>")
		)
		(pad "240" smd rect
			(at 2.050034 22.524974 90)
			(size 0.519938 1.4986)
			(layers "F.Cu" "F.Mask" "F.Paste")
			(net "GND")
		)
		(pad "241" smd rect
			(at 2.050034 23.375112 90)
			(size 0.519938 1.4986)
			(layers "F.Cu" "F.Mask" "F.Paste")
			(net "M_A_CPU1_SB_CB<2>")
		)
		(pad "242" smd rect
			(at 2.050034 24.224996 90)
			(size 0.519938 1.4986)
			(layers "F.Cu" "F.Mask" "F.Paste")
			(net "GND")
		)
		(pad "243" smd rect
			(at 2.050034 25.07488 90)
			(size 0.519938 1.4986)
			(layers "F.Cu" "F.Mask" "F.Paste")
			(net "M_A_CPU1_SB_CB<3>")
		)
		(pad "244" smd rect
			(at 2.050034 25.925018 90)
			(size 0.519938 1.4986)
			(layers "F.Cu" "F.Mask" "F.Paste")
			(net "GND")
		)
		(pad "245" smd rect
			(at 2.050034 26.774902 90)
			(size 0.519938 1.4986)
			(layers "F.Cu" "F.Mask" "F.Paste")
			(net "M_A_CPU1_SB_DQ<2>")
		)
		(pad "246" smd rect
			(at 2.050034 27.62504 90)
			(size 0.519938 1.4986)
			(layers "F.Cu" "F.Mask" "F.Paste")
			(net "GND")
		)
		(pad "247" smd rect
			(at 2.050034 28.474924 90)
			(size 0.519938 1.4986)
			(layers "F.Cu" "F.Mask" "F.Paste")
			(net "M_A_CPU1_SB_DQ<3>")
		)
		(pad "248" smd rect
			(at 2.050034 29.325062 90)
			(size 0.519938 1.4986)
			(layers "F.Cu" "F.Mask" "F.Paste")
			(net "GND")
		)
		(pad "249" smd rect
			(at 2.050034 30.174946 90)
			(size 0.519938 1.4986)
			(layers "F.Cu" "F.Mask" "F.Paste")
			(net "M_A_CPU1_SB_DQS_DN<5>")
		)
		(pad "250" smd rect
			(at 2.050034 31.025084 90)
			(size 0.519938 1.4986)
			(layers "F.Cu" "F.Mask" "F.Paste")
			(net "M_A_CPU1_SB_DQS_DP<5>")
		)
		(pad "251" smd rect
			(at 2.050034 31.874968 90)
			(size 0.519938 1.4986)
			(layers "F.Cu" "F.Mask" "F.Paste")
			(net "GND")
		)
		(pad "252" smd rect
			(at 2.050034 32.725106 90)
			(size 0.519938 1.4986)
			(layers "F.Cu" "F.Mask" "F.Paste")
			(net "M_A_CPU1_SB_DQ<6>")
		)
		(pad "253" smd rect
			(at 2.050034 33.57499 90)
			(size 0.519938 1.4986)
			(layers "F.Cu" "F.Mask" "F.Paste")
			(net "GND")
		)
		(pad "254" smd rect
			(at 2.050034 34.425128 90)
			(size 0.519938 1.4986)
			(layers "F.Cu" "F.Mask" "F.Paste")
			(net "M_A_CPU1_SB_DQ<7>")
		)
		(pad "255" smd rect
			(at 2.050034 35.275012 90)
			(size 0.519938 1.4986)
			(layers "F.Cu" "F.Mask" "F.Paste")
			(net "GND")
		)
		(pad "256" smd rect
			(at 2.050034 36.124896 90)
			(size 0.519938 1.4986)
			(layers "F.Cu" "F.Mask" "F.Paste")
			(net "M_A_CPU1_SB_DQ<10>")
		)
		(pad "257" smd rect
			(at 2.050034 36.975034 90)
			(size 0.519938 1.4986)
			(layers "F.Cu" "F.Mask" "F.Paste")
			(net "GND")
		)
		(pad "258" smd rect
			(at 2.050034 37.824918 90)
			(size 0.519938 1.4986)
			(layers "F.Cu" "F.Mask" "F.Paste")
			(net "M_A_CPU1_SB_DQ<11>")
		)
		(pad "259" smd rect
			(at 2.050034 38.675056 90)
			(size 0.519938 1.4986)
			(layers "F.Cu" "F.Mask" "F.Paste")
			(net "GND")
		)
		(pad "260" smd rect
			(at 2.050034 39.52494 90)
			(size 0.519938 1.4986)
			(layers "F.Cu" "F.Mask" "F.Paste")
			(net "M_A_CPU1_SB_DQS_DN<6>")
		)
		(pad "261" smd rect
			(at 2.050034 40.375078 90)
			(size 0.519938 1.4986)
			(layers "F.Cu" "F.Mask" "F.Paste")
			(net "M_A_CPU1_SB_DQS_DP<6>")
		)
		(pad "262" smd rect
			(at 2.050034 41.224962 90)
			(size 0.519938 1.4986)
			(layers "F.Cu" "F.Mask" "F.Paste")
			(net "GND")
		)
		(pad "263" smd rect
			(at 2.050034 42.0751 90)
			(size 0.519938 1.4986)
			(layers "F.Cu" "F.Mask" "F.Paste")
			(net "M_A_CPU1_SB_DQ<14>")
		)
		(pad "264" smd rect
			(at 2.050034 42.924984 90)
			(size 0.519938 1.4986)
			(layers "F.Cu" "F.Mask" "F.Paste")
			(net "GND")
		)
		(pad "265" smd rect
			(at 2.050034 43.775122 90)
			(size 0.519938 1.4986)
			(layers "F.Cu" "F.Mask" "F.Paste")
			(net "M_A_CPU1_SB_DQ<15>")
		)
		(pad "266" smd rect
			(at 2.050034 44.625006 90)
			(size 0.519938 1.4986)
			(layers "F.Cu" "F.Mask" "F.Paste")
			(net "GND")
		)
		(pad "267" smd rect
			(at 2.050034 45.47489 90)
			(size 0.519938 1.4986)
			(layers "F.Cu" "F.Mask" "F.Paste")
			(net "M_A_CPU1_SB_DQ<18>")
		)
		(pad "268" smd rect
			(at 2.050034 46.325028 90)
			(size 0.519938 1.4986)
			(layers "F.Cu" "F.Mask" "F.Paste")
			(net "GND")
		)
		(pad "269" smd rect
			(at 2.050034 47.174912 90)
			(size 0.519938 1.4986)
			(layers "F.Cu" "F.Mask" "F.Paste")
			(net "M_A_CPU1_SB_DQ<19>")
		)
		(pad "270" smd rect
			(at 2.050034 48.02505 90)
			(size 0.519938 1.4986)
			(layers "F.Cu" "F.Mask" "F.Paste")
			(net "GND")
		)
		(pad "271" smd rect
			(at 2.050034 48.874934 90)
			(size 0.519938 1.4986)
			(layers "F.Cu" "F.Mask" "F.Paste")
			(net "M_A_CPU1_SB_DQS_DN<7>")
		)
		(pad "272" smd rect
			(at 2.050034 49.725072 90)
			(size 0.519938 1.4986)
			(layers "F.Cu" "F.Mask" "F.Paste")
			(net "M_A_CPU1_SB_DQS_DP<7>")
		)
		(pad "273" smd rect
			(at 2.050034 50.574956 90)
			(size 0.519938 1.4986)
			(layers "F.Cu" "F.Mask" "F.Paste")
			(net "GND")
		)
		(pad "274" smd rect
			(at 2.050034 51.425094 90)
			(size 0.519938 1.4986)
			(layers "F.Cu" "F.Mask" "F.Paste")
			(net "M_A_CPU1_SB_DQ<22>")
		)
		(pad "275" smd rect
			(at 2.050034 52.274978 90)
			(size 0.519938 1.4986)
			(layers "F.Cu" "F.Mask" "F.Paste")
			(net "GND")
		)
		(pad "276" smd rect
			(at 2.050034 53.125116 90)
			(size 0.519938 1.4986)
			(layers "F.Cu" "F.Mask" "F.Paste")
			(net "M_A_CPU1_SB_DQ<23>")
		)
		(pad "277" smd rect
			(at 2.050034 53.975 90)
			(size 0.519938 1.4986)
			(layers "F.Cu" "F.Mask" "F.Paste")
			(net "GND")
		)
		(pad "278" smd rect
			(at 2.050034 54.824884 90)
			(size 0.519938 1.4986)
			(layers "F.Cu" "F.Mask" "F.Paste")
			(net "M_A_CPU1_SB_DQ<26>")
		)
		(pad "279" smd rect
			(at 2.050034 55.675022 90)
			(size 0.519938 1.4986)
			(layers "F.Cu" "F.Mask" "F.Paste")
			(net "GND")
		)
		(pad "280" smd rect
			(at 2.050034 56.524906 90)
			(size 0.519938 1.4986)
			(layers "F.Cu" "F.Mask" "F.Paste")
			(net "M_A_CPU1_SB_DQ<27>")
		)
		(pad "281" smd rect
			(at 2.050034 57.375044 90)
			(size 0.519938 1.4986)
			(layers "F.Cu" "F.Mask" "F.Paste")
			(net "GND")
		)
		(pad "282" smd rect
			(at 2.050034 58.224928 90)
			(size 0.519938 1.4986)
			(layers "F.Cu" "F.Mask" "F.Paste")
			(net "M_A_CPU1_SB_DQS_DN<8>")
		)
		(pad "283" smd rect
			(at 2.050034 59.075066 90)
			(size 0.519938 1.4986)
			(layers "F.Cu" "F.Mask" "F.Paste")
			(net "M_A_CPU1_SB_DQS_DP<8>")
		)
		(pad "284" smd rect
			(at 2.050034 59.92495 90)
			(size 0.519938 1.4986)
			(layers "F.Cu" "F.Mask" "F.Paste")
			(net "GND")
		)
		(pad "285" smd rect
			(at 2.050034 60.775088 90)
			(size 0.519938 1.4986)
			(layers "F.Cu" "F.Mask" "F.Paste")
			(net "M_A_CPU1_SB_DQ<30>")
		)
		(pad "286" smd rect
			(at 2.050034 61.624972 90)
			(size 0.519938 1.4986)
			(layers "F.Cu" "F.Mask" "F.Paste")
			(net "GND")
		)
		(pad "287" smd rect
			(at 2.050034 62.47511 90)
			(size 0.519938 1.4986)
			(layers "F.Cu" "F.Mask" "F.Paste")
			(net "M_A_CPU1_SB_DQ<31>")
		)
		(pad "288" smd rect
			(at 2.050034 63.324994 90)
			(size 0.519938 1.4986)
			(layers "F.Cu" "F.Mask" "F.Paste")
			(net "GND")
		)
		(pad "G1" thru_hole oval
			(at 0 -68.97497 90)
			(size 1.7272 3.4798)
			(drill oval 1.2192 2.4638)
			(layers "*.Cu" "*.Mask")
			(remove_unused_layers no)
			(net "GND")
			(clearance 0.127)
			(thermal_gap 0.127)
		)
		(pad "G2" thru_hole oval
			(at 0 3.875024 90)
			(size 1.7272 3.4798)
			(drill oval 1.2192 2.4638)
			(layers "*.Cu" "*.Mask")
			(remove_unused_layers no)
			(net "GND")
			(clearance 0.127)
			(thermal_gap 0.127)
		)
		(pad "G3" thru_hole oval
			(at 0 68.97497 90)
			(size 1.7272 3.4798)
			(drill oval 1.2192 2.4638)
			(layers "*.Cu" "*.Mask")
			(remove_unused_layers no)
			(net "GND")
			(clearance 0.127)
			(thermal_gap 0.127)
		)
	)
)
